(kicad_pcb
	(version 20260206)
	(generator "pcbnew")
	(generator_version "10.0")
	(general
		(thickness 1.6)
		(legacy_teardrops no)
	)
	(paper "A4")
	(title_block
		(title "01162023_DA0F0TEBIF0_F0T_Expander_BD_F_brd_V02_OCP.brd")
		(comment 1 "Grand Teton / footprints 8243-8253 of 9728")
	)
	(layers
		(0 "F.Cu" signal "TOP")
		(4 "In1.Cu" signal "GND")
		(6 "In2.Cu" signal "VCC")
		(8 "In3.Cu" signal "VCC1")
		(10 "In4.Cu" signal "GND1")
		(12 "In5.Cu" signal "IN1")
		(14 "In6.Cu" signal "GND2")
		(16 "In7.Cu" signal "IN2")
		(18 "In8.Cu" signal "GND3")
		(20 "In9.Cu" signal "IN3")
		(22 "In10.Cu" signal "GND4")
		(24 "In11.Cu" signal "IN4")
		(26 "In12.Cu" signal "GND5")
		(28 "In13.Cu" signal "IN5")
		(30 "In14.Cu" signal "GND6")
		(32 "In15.Cu" signal "IN6")
		(34 "In16.Cu" signal "GND7")
		(2 "B.Cu" signal "BOTTOM")
		(9 "F.Adhes" user "F.Adhesive")
		(11 "B.Adhes" user "B.Adhesive")
		(13 "F.Paste" user "Package Geometry/Pastemask Top")
		(15 "B.Paste" user "Package Geometry/Pastemask Bottom")
		(5 "F.SilkS" user "Ref Des/Silkscreen Top")
		(7 "B.SilkS" user "Ref Des/Silkscreen Bottom")
		(1 "F.Mask" user "Board Geometry/Soldermask Top")
		(3 "B.Mask" user "Board Geometry/Soldermask Bottom")
		(17 "Dwgs.User" user "User.Drawings")
		(19 "Cmts.User" user "User.Comments")
		(21 "Eco1.User" user "User.Eco1")
		(23 "Eco2.User" user "User.Eco2")
		(25 "Edge.Cuts" user "Board Geometry/Outline")
		(27 "Margin" user)
		(31 "F.CrtYd" user "Package Geometry/Place Bound Top")
		(29 "B.CrtYd" user "Package Geometry/Place Bound Bottom")
		(35 "F.Fab" user "Ref Des/Assembly Top")
		(33 "B.Fab" user "Ref Des/Assembly Bottom")
	)
	(footprint ""
		(layer "B.Cu")
		(at 6.93166 -386.784596 180)
		(property "Reference" "C4467"
			(at 0 0 0)
			(layer "B.SilkS")
			(hide yes)
			(effects
				(font
					(size 1.27 1.27)
				)
				(justify mirror)
			)
		)
		(property "Value" ""
			(at 0 0 0)
			(layer "B.Fab")
			(effects
				(font
					(size 1.27 1.27)
				)
				(justify mirror)
			)
		)
		(duplicate_pad_numbers_are_jumpers no)
		(fp_line
			(start 0.7874 0.4064)
			(end 0.7874 -0.4064)
			(stroke
				(width 0.1524)
				(type default)
			)
			(layer "B.SilkS")
		)
		(fp_line
			(start 0.7874 -0.4064)
			(end -0.7874 -0.4064)
			(stroke
				(width 0.1524)
				(type default)
			)
			(layer "B.SilkS")
		)
		(fp_line
			(start -0.7874 0.4064)
			(end 0.7874 0.4064)
			(stroke
				(width 0.1524)
				(type default)
			)
			(layer "B.SilkS")
		)
		(fp_line
			(start -0.7874 -0.4064)
			(end -0.7874 0.4064)
			(stroke
				(width 0.1524)
				(type default)
			)
			(layer "B.SilkS")
		)
		(fp_line
			(start 0.67945 0.3048)
			(end 0.67945 -0.305054)
			(stroke
				(width 0.1)
				(type default)
			)
			(layer "B.Fab")
		)
		(fp_line
			(start 0.67945 -0.305054)
			(end 0.12065 -0.305054)
			(stroke
				(width 0.1)
				(type default)
			)
			(layer "B.Fab")
		)
		(fp_line
			(start 0.12065 0.3048)
			(end 0.67945 0.3048)
			(stroke
				(width 0.1)
				(type default)
			)
			(layer "B.Fab")
		)
		(fp_line
			(start 0.12065 0.2794)
			(end 0.12065 0.3048)
			(stroke
				(width 0.1)
				(type default)
			)
			(layer "B.Fab")
		)
		(fp_line
			(start 0.12065 -0.2794)
			(end -0.12065 -0.2794)
			(stroke
				(width 0.1)
				(type default)
			)
			(layer "B.Fab")
		)
		(fp_line
			(start 0.12065 -0.305054)
			(end 0.12065 -0.2794)
			(stroke
				(width 0.1)
				(type default)
			)
			(layer "B.Fab")
		)
		(fp_line
			(start -0.120396 0.3048)
			(end -0.120396 0.2794)
			(stroke
				(width 0.1)
				(type default)
			)
			(layer "B.Fab")
		)
		(fp_line
			(start -0.120396 0.2794)
			(end 0.12065 0.2794)
			(stroke
				(width 0.1)
				(type default)
			)
			(layer "B.Fab")
		)
		(fp_line
			(start -0.12065 -0.2794)
			(end -0.12065 -0.3048)
			(stroke
				(width 0.1)
				(type default)
			)
			(layer "B.Fab")
		)
		(fp_line
			(start -0.12065 -0.3048)
			(end -0.67945 -0.3048)
			(stroke
				(width 0.1)
				(type default)
			)
			(layer "B.Fab")
		)
		(fp_line
			(start -0.67945 0.3048)
			(end -0.120396 0.3048)
			(stroke
				(width 0.1)
				(type default)
			)
			(layer "B.Fab")
		)
		(fp_line
			(start -0.67945 -0.3048)
			(end -0.67945 0.3048)
			(stroke
				(width 0.1)
				(type default)
			)
			(layer "B.Fab")
		)
		(pad "1" smd circle
			(at 0.40005 0)
			(size 0 0)
			(layers "B.Cu" "B.Mask" "B.Paste")
			(net "P1V2_USB_8042")
		)
		(pad "2" smd circle
			(at -0.40005 0)
			(size 0 0)
			(layers "B.Cu" "B.Mask" "B.Paste")
			(net "GND")
		)
	)
	(footprint ""
		(layer "B.Cu")
		(at 401.299934 -303.499774 -90)
		(property "Reference" "C3437"
			(at 0 0 90)
			(layer "B.SilkS")
			(hide yes)
			(effects
				(font
					(size 1.27 1.27)
				)
				(justify mirror)
			)
		)
		(property "Value" ""
			(at 0 0 90)
			(layer "B.Fab")
			(effects
				(font
					(size 1.27 1.27)
				)
				(justify mirror)
			)
		)
		(duplicate_pad_numbers_are_jumpers no)
		(fp_line
			(start -0.299974 0.150114)
			(end 0.299974 0.150114)
			(stroke
				(width 0.1)
				(type default)
			)
			(layer "B.Fab")
		)
		(fp_line
			(start 0.299974 0.150114)
			(end 0.299974 -0.150114)
			(stroke
				(width 0.1)
				(type default)
			)
			(layer "B.Fab")
		)
		(fp_line
			(start -0.299974 -0.150114)
			(end -0.299974 0.150114)
			(stroke
				(width 0.1)
				(type default)
			)
			(layer "B.Fab")
		)
		(fp_line
			(start 0.299974 -0.150114)
			(end -0.299974 -0.150114)
			(stroke
				(width 0.1)
				(type default)
			)
			(layer "B.Fab")
		)
		(pad "1" smd rect
			(at 0.2667 0 90)
			(size 0.3048 0.381)
			(layers "B.Cu" "B.Mask" "B.Paste")
			(net "P1V25_PEX3")
		)
		(pad "2" smd rect
			(at -0.2667 0 90)
			(size 0.3048 0.381)
			(layers "B.Cu" "B.Mask" "B.Paste")
			(net "GND")
		)
	)
	(footprint ""
		(layer "B.Cu")
		(at 417.450016 -302.074834)
		(property "Reference" "C3516"
			(at 0 0 0)
			(layer "B.SilkS")
			(hide yes)
			(effects
				(font
					(size 1.27 1.27)
				)
				(justify mirror)
			)
		)
		(property "Value" ""
			(at 0 0 0)
			(layer "B.Fab")
			(effects
				(font
					(size 1.27 1.27)
				)
				(justify mirror)
			)
		)
		(duplicate_pad_numbers_are_jumpers no)
		(fp_line
			(start -0.299974 -0.150114)
			(end -0.299974 0.150114)
			(stroke
				(width 0.1)
				(type default)
			)
			(layer "B.Fab")
		)
		(fp_line
			(start -0.299974 0.150114)
			(end 0.299974 0.150114)
			(stroke
				(width 0.1)
				(type default)
			)
			(layer "B.Fab")
		)
		(fp_line
			(start 0.299974 -0.150114)
			(end -0.299974 -0.150114)
			(stroke
				(width 0.1)
				(type default)
			)
			(layer "B.Fab")
		)
		(fp_line
			(start 0.299974 0.150114)
			(end 0.299974 -0.150114)
			(stroke
				(width 0.1)
				(type default)
			)
			(layer "B.Fab")
		)
		(pad "1" smd rect
			(at 0.2667 0 180)
			(size 0.3048 0.381)
			(layers "B.Cu" "B.Mask" "B.Paste")
			(net "P1V8_PEX")
		)
		(pad "2" smd rect
			(at -0.2667 0 180)
			(size 0.3048 0.381)
			(layers "B.Cu" "B.Mask" "B.Paste")
			(net "GND")
		)
	)
	(footprint ""
		(layer "B.Cu")
		(at 179.07508 -297.79976 -90)
		(property "Reference" "C1398"
			(at 0 0 90)
			(layer "B.SilkS")
			(hide yes)
			(effects
				(font
					(size 1.27 1.27)
				)
				(justify mirror)
			)
		)
		(property "Value" ""
			(at 0 0 90)
			(layer "B.Fab")
			(effects
				(font
					(size 1.27 1.27)
				)
				(justify mirror)
			)
		)
		(duplicate_pad_numbers_are_jumpers no)
		(fp_line
			(start -0.299974 0.150114)
			(end 0.299974 0.150114)
			(stroke
				(width 0.1)
				(type default)
			)
			(layer "B.Fab")
		)
		(fp_line
			(start 0.299974 0.150114)
			(end 0.299974 -0.150114)
			(stroke
				(width 0.1)
				(type default)
			)
			(layer "B.Fab")
		)
		(fp_line
			(start -0.299974 -0.150114)
			(end -0.299974 0.150114)
			(stroke
				(width 0.1)
				(type default)
			)
			(layer "B.Fab")
		)
		(fp_line
			(start 0.299974 -0.150114)
			(end -0.299974 -0.150114)
			(stroke
				(width 0.1)
				(type default)
			)
			(layer "B.Fab")
		)
		(pad "1" smd rect
			(at 0.2667 0 90)
			(size 0.3048 0.381)
			(layers "B.Cu" "B.Mask" "B.Paste")
			(net "P0V8_PEX1")
		)
		(pad "2" smd rect
			(at -0.2667 0 90)
			(size 0.3048 0.381)
			(layers "B.Cu" "B.Mask" "B.Paste")
			(net "GND")
		)
	)
	(footprint ""
		(layer "B.Cu")
		(at 185.250074 -297.32478 180)
		(property "Reference" "C1421"
			(at 0 0 0)
			(layer "B.SilkS")
			(hide yes)
			(effects
				(font
					(size 1.27 1.27)
				)
				(justify mirror)
			)
		)
		(property "Value" ""
			(at 0 0 0)
			(layer "B.Fab")
			(effects
				(font
					(size 1.27 1.27)
				)
				(justify mirror)
			)
		)
		(duplicate_pad_numbers_are_jumpers no)
		(fp_line
			(start 0.299974 0.150114)
			(end 0.299974 -0.150114)
			(stroke
				(width 0.1)
				(type default)
			)
			(layer "B.Fab")
		)
		(fp_line
			(start 0.299974 -0.150114)
			(end -0.299974 -0.150114)
			(stroke
				(width 0.1)
				(type default)
			)
			(layer "B.Fab")
		)
		(fp_line
			(start -0.299974 0.150114)
			(end 0.299974 0.150114)
			(stroke
				(width 0.1)
				(type default)
			)
			(layer "B.Fab")
		)
		(fp_line
			(start -0.299974 -0.150114)
			(end -0.299974 0.150114)
			(stroke
				(width 0.1)
				(type default)
			)
			(layer "B.Fab")
		)
		(pad "1" smd rect
			(at 0.2667 0)
			(size 0.3048 0.381)
			(layers "B.Cu" "B.Mask" "B.Paste")
			(net "P0V8_SERDES_VDDA_PEX1")
		)
		(pad "2" smd rect
			(at -0.2667 0)
			(size 0.3048 0.381)
			(layers "B.Cu" "B.Mask" "B.Paste")
			(net "GND")
		)
	)
	(footprint ""
		(layer "B.Cu")
		(at 364.855506 -321.85229 -90)
		(property "Reference" "R6547"
			(at 0 0 90)
			(layer "B.SilkS")
			(hide yes)
			(effects
				(font
					(size 1.27 1.27)
				)
				(justify mirror)
			)
		)
		(property "Value" ""
			(at 0 0 90)
			(layer "B.Fab")
			(effects
				(font
					(size 1.27 1.27)
				)
				(justify mirror)
			)
		)
		(duplicate_pad_numbers_are_jumpers no)
		(fp_line
			(start -0.7874 0.4064)
			(end 0.7874 0.4064)
			(stroke
				(width 0.1524)
				(type default)
			)
			(layer "B.SilkS")
		)
		(fp_line
			(start 0.7874 0.4064)
			(end 0.7874 -0.4064)
			(stroke
				(width 0.1524)
				(type default)
			)
			(layer "B.SilkS")
		)
		(fp_line
			(start -0.7874 -0.4064)
			(end -0.7874 0.4064)
			(stroke
				(width 0.1524)
				(type default)
			)
			(layer "B.SilkS")
		)
		(fp_line
			(start 0.7874 -0.4064)
			(end -0.7874 -0.4064)
			(stroke
				(width 0.1524)
				(type default)
			)
			(layer "B.SilkS")
		)
		(fp_line
			(start -0.67945 0.3048)
			(end -0.120396 0.3048)
			(stroke
				(width 0.1)
				(type default)
			)
			(layer "B.Fab")
		)
		(fp_line
			(start -0.120396 0.3048)
			(end -0.120396 0.2794)
			(stroke
				(width 0.1)
				(type default)
			)
			(layer "B.Fab")
		)
		(fp_line
			(start 0.12065 0.3048)
			(end 0.67945 0.3048)
			(stroke
				(width 0.1)
				(type default)
			)
			(layer "B.Fab")
		)
		(fp_line
			(start 0.67945 0.3048)
			(end 0.67945 -0.305054)
			(stroke
				(width 0.1)
				(type default)
			)
			(layer "B.Fab")
		)
		(fp_line
			(start -0.120396 0.2794)
			(end 0.12065 0.2794)
			(stroke
				(width 0.1)
				(type default)
			)
			(layer "B.Fab")
		)
		(fp_line
			(start 0.12065 0.2794)
			(end 0.12065 0.3048)
			(stroke
				(width 0.1)
				(type default)
			)
			(layer "B.Fab")
		)
		(fp_line
			(start -0.12065 -0.2794)
			(end -0.12065 -0.3048)
			(stroke
				(width 0.1)
				(type default)
			)
			(layer "B.Fab")
		)
		(fp_line
			(start 0.12065 -0.2794)
			(end -0.12065 -0.2794)
			(stroke
				(width 0.1)
				(type default)
			)
			(layer "B.Fab")
		)
		(fp_line
			(start -0.67945 -0.3048)
			(end -0.67945 0.3048)
			(stroke
				(width 0.1)
				(type default)
			)
			(layer "B.Fab")
		)
		(fp_line
			(start -0.12065 -0.3048)
			(end -0.67945 -0.3048)
			(stroke
				(width 0.1)
				(type default)
			)
			(layer "B.Fab")
		)
		(fp_line
			(start 0.12065 -0.305054)
			(end 0.12065 -0.2794)
			(stroke
				(width 0.1)
				(type default)
			)
			(layer "B.Fab")
		)
		(fp_line
			(start 0.67945 -0.305054)
			(end 0.12065 -0.305054)
			(stroke
				(width 0.1)
				(type default)
			)
			(layer "B.Fab")
		)
		(pad "1" smd circle
			(at 0.40005 0 90)
			(size 0 0)
			(layers "B.Cu" "B.Mask" "B.Paste")
			(net "P0V8_SERDES_VDDA_PEX3")
		)
		(pad "2" smd circle
			(at -0.40005 0 90)
			(size 0 0)
			(layers "B.Cu" "B.Mask" "B.Paste")
			(net "P0V8_SERDES_VDDA_PEX3_C10")
		)
	)
	(footprint ""
		(layer "B.Cu")
		(at 177.649886 -301.599854 -90)
		(property "Reference" "C1494"
			(at 0 0 90)
			(layer "B.SilkS")
			(hide yes)
			(effects
				(font
					(size 1.27 1.27)
				)
				(justify mirror)
			)
		)
		(property "Value" ""
			(at 0 0 90)
			(layer "B.Fab")
			(effects
				(font
					(size 1.27 1.27)
				)
				(justify mirror)
			)
		)
		(duplicate_pad_numbers_are_jumpers no)
		(fp_line
			(start -0.299974 0.150114)
			(end 0.299974 0.150114)
			(stroke
				(width 0.1)
				(type default)
			)
			(layer "B.Fab")
		)
		(fp_line
			(start 0.299974 0.150114)
			(end 0.299974 -0.150114)
			(stroke
				(width 0.1)
				(type default)
			)
			(layer "B.Fab")
		)
		(fp_line
			(start -0.299974 -0.150114)
			(end -0.299974 0.150114)
			(stroke
				(width 0.1)
				(type default)
			)
			(layer "B.Fab")
		)
		(fp_line
			(start 0.299974 -0.150114)
			(end -0.299974 -0.150114)
			(stroke
				(width 0.1)
				(type default)
			)
			(layer "B.Fab")
		)
		(pad "1" smd rect
			(at 0.2667 0 90)
			(size 0.3048 0.381)
			(layers "B.Cu" "B.Mask" "B.Paste")
			(net "P0V8_SERDES_VDDA_PEX1")
		)
		(pad "2" smd rect
			(at -0.2667 0 90)
			(size 0.3048 0.381)
			(layers "B.Cu" "B.Mask" "B.Paste")
			(net "GND")
		)
	)
	(footprint ""
		(layer "B.Cu")
		(at 125.704346 -325.61149 -90)
		(property "Reference" "C4254"
			(at 0 0 90)
			(layer "B.SilkS")
			(hide yes)
			(effects
				(font
					(size 1.27 1.27)
				)
				(justify mirror)
			)
		)
		(property "Value" ""
			(at 0 0 90)
			(layer "B.Fab")
			(effects
				(font
					(size 1.27 1.27)
				)
				(justify mirror)
			)
		)
		(duplicate_pad_numbers_are_jumpers no)
		(fp_line
			(start -1.2954 0.5842)
			(end 1.2954 0.5842)
			(stroke
				(width 0.1524)
				(type default)
			)
			(layer "B.SilkS")
		)
		(fp_line
			(start 1.2954 0.5842)
			(end 1.2954 -0.5842)
			(stroke
				(width 0.1524)
				(type default)
			)
			(layer "B.SilkS")
		)
		(fp_line
			(start -1.2954 -0.5842)
			(end -1.2954 0.5842)
			(stroke
				(width 0.1524)
				(type default)
			)
			(layer "B.SilkS")
		)
		(fp_line
			(start 1.2954 -0.5842)
			(end -1.2954 -0.5842)
			(stroke
				(width 0.1524)
				(type default)
			)
			(layer "B.SilkS")
		)
		(fp_line
			(start -0.8636 0.4572)
			(end 0.8636 0.4572)
			(stroke
				(width 0.1)
				(type default)
			)
			(layer "B.Fab")
		)
		(fp_line
			(start 0.8636 0.4572)
			(end 0.8636 0.4064)
			(stroke
				(width 0.1)
				(type default)
			)
			(layer "B.Fab")
		)
		(fp_line
			(start -1.1938 0.4064)
			(end -0.8636 0.4064)
			(stroke
				(width 0.1)
				(type default)
			)
			(layer "B.Fab")
		)
		(fp_line
			(start -0.8636 0.4064)
			(end -0.8636 0.4572)
			(stroke
				(width 0.1)
				(type default)
			)
			(layer "B.Fab")
		)
		(fp_line
			(start 0.8636 0.4064)
			(end 1.1938 0.4064)
			(stroke
				(width 0.1)
				(type default)
			)
			(layer "B.Fab")
		)
		(fp_line
			(start 1.1938 0.4064)
			(end 1.1938 -0.4064)
			(stroke
				(width 0.1)
				(type default)
			)
			(layer "B.Fab")
		)
		(fp_line
			(start -1.1938 -0.4064)
			(end -1.1938 0.4064)
			(stroke
				(width 0.1)
				(type default)
			)
			(layer "B.Fab")
		)
		(fp_line
			(start -0.8636 -0.4064)
			(end -1.1938 -0.4064)
			(stroke
				(width 0.1)
				(type default)
			)
			(layer "B.Fab")
		)
		(fp_line
			(start 0.8636 -0.4064)
			(end 0.8636 -0.4572)
			(stroke
				(width 0.1)
				(type default)
			)
			(layer "B.Fab")
		)
		(fp_line
			(start 1.1938 -0.4064)
			(end 0.8636 -0.4064)
			(stroke
				(width 0.1)
				(type default)
			)
			(layer "B.Fab")
		)
		(fp_line
			(start -0.8636 -0.4572)
			(end -0.8636 -0.4064)
			(stroke
				(width 0.1)
				(type default)
			)
			(layer "B.Fab")
		)
		(fp_line
			(start 0.8636 -0.4572)
			(end -0.8636 -0.4572)
			(stroke
				(width 0.1)
				(type default)
			)
			(layer "B.Fab")
		)
		(pad "1" smd rect
			(at 0.7366 0 180)
			(size 0.7112 0.8128)
			(layers "B.Cu" "B.Mask" "B.Paste")
			(net "P0V8_SERDES_VDDA_PEX1_C0")
		)
		(pad "2" smd rect
			(at -0.7366 0 180)
			(size 0.7112 0.8128)
			(layers "B.Cu" "B.Mask" "B.Paste")
			(net "GND")
		)
	)
	(footprint ""
		(layer "B.Cu")
		(at 186.941714 -300.174914)
		(property "Reference" "C3187"
			(at 0 0 0)
			(layer "B.SilkS")
			(hide yes)
			(effects
				(font
					(size 1.27 1.27)
				)
				(justify mirror)
			)
		)
		(property "Value" ""
			(at 0 0 0)
			(layer "B.Fab")
			(effects
				(font
					(size 1.27 1.27)
				)
				(justify mirror)
			)
		)
		(duplicate_pad_numbers_are_jumpers no)
		(fp_line
			(start -0.299974 -0.150114)
			(end -0.299974 0.150114)
			(stroke
				(width 0.1)
				(type default)
			)
			(layer "B.Fab")
		)
		(fp_line
			(start -0.299974 0.150114)
			(end 0.299974 0.150114)
			(stroke
				(width 0.1)
				(type default)
			)
			(layer "B.Fab")
		)
		(fp_line
			(start 0.299974 -0.150114)
			(end -0.299974 -0.150114)
			(stroke
				(width 0.1)
				(type default)
			)
			(layer "B.Fab")
		)
		(fp_line
			(start 0.299974 0.150114)
			(end 0.299974 -0.150114)
			(stroke
				(width 0.1)
				(type default)
			)
			(layer "B.Fab")
		)
		(pad "1" smd rect
			(at 0.2667 0 180)
			(size 0.3048 0.381)
			(layers "B.Cu" "B.Mask" "B.Paste")
			(net "P1V8_VDDA_PEX1")
		)
		(pad "2" smd rect
			(at -0.2667 0 180)
			(size 0.3048 0.381)
			(layers "B.Cu" "B.Mask" "B.Paste")
			(net "GND")
		)
	)
	(footprint ""
		(layer "B.Cu")
		(at 410.324808 -297.79976 90)
		(property "Reference" "C1914"
			(at 0 0 90)
			(layer "B.SilkS")
			(hide yes)
			(effects
				(font
					(size 1.27 1.27)
				)
				(justify mirror)
			)
		)
		(property "Value" ""
			(at 0 0 90)
			(layer "B.Fab")
			(effects
				(font
					(size 1.27 1.27)
				)
				(justify mirror)
			)
		)
		(duplicate_pad_numbers_are_jumpers no)
		(fp_line
			(start 0.299974 -0.150114)
			(end -0.299974 -0.150114)
			(stroke
				(width 0.1)
				(type default)
			)
			(layer "B.Fab")
		)
		(fp_line
			(start -0.299974 -0.150114)
			(end -0.299974 0.150114)
			(stroke
				(width 0.1)
				(type default)
			)
			(layer "B.Fab")
		)
		(fp_line
			(start 0.299974 0.150114)
			(end 0.299974 -0.150114)
			(stroke
				(width 0.1)
				(type default)
			)
			(layer "B.Fab")
		)
		(fp_line
			(start -0.299974 0.150114)
			(end 0.299974 0.150114)
			(stroke
				(width 0.1)
				(type default)
			)
			(layer "B.Fab")
		)
		(pad "1" smd rect
			(at 0.2667 0 270)
			(size 0.3048 0.381)
			(layers "B.Cu" "B.Mask" "B.Paste")
			(net "P0V8_PEX3")
		)
		(pad "2" smd rect
			(at -0.2667 0 270)
			(size 0.3048 0.381)
			(layers "B.Cu" "B.Mask" "B.Paste")
			(net "GND")
		)
	)
	(footprint ""
		(layer "B.Cu")
		(at 296.124884 -286.399732 90)
		(property "Reference" "C3312"
			(at 0 0 90)
			(layer "B.SilkS")
			(hide yes)
			(effects
				(font
					(size 1.27 1.27)
				)
				(justify mirror)
			)
		)
		(property "Value" ""
			(at 0 0 90)
			(layer "B.Fab")
			(effects
				(font
					(size 1.27 1.27)
				)
				(justify mirror)
			)
		)
		(duplicate_pad_numbers_are_jumpers no)
		(fp_line
			(start 0.299974 -0.150114)
			(end -0.299974 -0.150114)
			(stroke
				(width 0.1)
				(type default)
			)
			(layer "B.Fab")
		)
		(fp_line
			(start -0.299974 -0.150114)
			(end -0.299974 0.150114)
			(stroke
				(width 0.1)
				(type default)
			)
			(layer "B.Fab")
		)
		(fp_line
			(start 0.299974 0.150114)
			(end 0.299974 -0.150114)
			(stroke
				(width 0.1)
				(type default)
			)
			(layer "B.Fab")
		)
		(fp_line
			(start -0.299974 0.150114)
			(end 0.299974 0.150114)
			(stroke
				(width 0.1)
				(type default)
			)
			(layer "B.Fab")
		)
		(pad "1" smd rect
			(at 0.2667 0 270)
			(size 0.3048 0.381)
			(layers "B.Cu" "B.Mask" "B.Paste")
			(net "P1V25_SERDES_VDDPLL_PEX2")
		)
		(pad "2" smd rect
			(at -0.2667 0 270)
			(size 0.3048 0.381)
			(layers "B.Cu" "B.Mask" "B.Paste")
			(net "GND")
		)
	)
)
